FILE_TYPE = CONNECTIVITY;
{Allegro Design Entry HDL 17.2-2016 S081 (4005846) 1/11/2022}
"PAGE_NUMBER" = 122;
0"NC";
END.
